FILE_TYPE = MACRO_DRAWING;
SET COLOR_WIRE YELLOW;
SET COLOR_PROP ORANGE;
SET COLOR_DOT WHITE;
SET COLOR_ARC YELLOW;
SET COLOR_BODY GREEN;
SET COLOR_NOTE PURPLE;
SET PROP_DISPLAY VALUE;
SET PAGE_NUMBER P441;
FORCEADD QUANTA_TITLE_BLOCK_C..1
(0 0);
FORCEPROP 1 LAST CUSTOM_TXT_CDS <NAME_2>
J 0
(-3175 50);
FORCEPROP 1 LAST CUSTOM_TXT_CDS <NAME_1>
J 0
(-3175 175);
FORCEPROP 1 LAST CUSTOM_TXT_CDS <Q_NUMBER>
J 0
(-1403 103);
DISPLAY 1.212766 (-1403 103);
FORCEPROP 1 LAST CUSTOM_TXT_CDS <Q_PROJ>
J 0
(-2382 102);
DISPLAY 1.212766 (-2382 102);
FORCEPROP 1 LAST CUSTOM_TXT_CDS <Q_REV>
J 0
(-184 103);
DISPLAY 1.212766 (-184 103);
FORCEPROP 1 LAST CUSTOM_TXT_CDS <CON_LAST_MODIFIED>
J 0
(-1885 15);
DISPLAY 0.978723 (-1885 15);
FORCEPROP 1 LAST CUSTOM_TXT_CDS <CON_PAGE_NUM> OF <CON_TOTAL_PAGES>
J 0
(-446 18);
DISPLAY 0.978723 (-446 18);
FORCEPROP 1 LAST Q_TITLE RETIMER_CPU1_P0(10)
J 0
(-9366 26);
DISPLAY 2.446809 (-9366 26);
PAINT GREEN (-9366 26);
FORCEPROP 2 LAST CDS_LIB pure_quanta
J 0
(0 0);
DISPLAY INVISIBLE (0 0);
FORCEPROP 1 LAST CDS_LMAN_SYM_OUTLINE -9475,6775,100,-125
J 0
(0 0);
DISPLAY 0.468085 (0 0);
PAINT GREEN (0 0);
DISPLAY INVISIBLE (0 0);
FORCEPROP 2 LAST PAGE_BORDER TRUE
J 0
(-7890 5250);
DISPLAY 0.638298 (-7890 5250);
PAINT PINK (-7890 5250);
DISPLAY INVISIBLE (-7890 5250);
FORCEPROP 2 LAST CDS_XR_PAGE_TITLE CR-326 : @T6G_MB_LIB.T6G(SCH_1):PAGE326
J 0
(-7890 5250);
DISPLAY 0.638298 (-7890 5250);
PAINT PINK (-7890 5250);
DISPLAY INVISIBLE (-7890 5250);
FORCEPROP 2 LAST CUSTOM_TXT_CDS <XR_PAGE_TITLE>
J 0
(-7890 5250);
DISPLAY 0.638298 (-7890 5250);
PAINT PINK (-7890 5250);
DISPLAY INVISIBLE (-7890 5250);
FORCEPROP 1 LAST COMMENT_BODY TRUE
J 0
(12 -13);
DISPLAY 0.978723 (12 -13);
PAINT GREEN (12 -13);
DISPLAY INVISIBLE (12 -13);
FORCEPROP 1 LAST Q_DEPT BU9
J 1
(-3763 49);
DISPLAY 1.957447 (-3763 49);
PAINT GREEN (-3763 49);
DISPLAY INVISIBLE (-3763 49);
FORCEPROP 0 LAST CDS_CON_LAST_MODIFIED Thu Aug 24 10:16:45 2023
J 0
(-1885 15);
DISPLAY INVISIBLE (-1885 15);
QUIT
